# S9S_MB_2U (Grand Teton) — schematic netlist excerpt (pin names and nets, part order shuffled) for the footprints in the layout excerpt that follows; sources: Cadence DE-HDL packaged netlist, KiCad conversion of 03242023_DA0F0TMBIJ0_F0T_Motherboard_J_brd_V01_OCP.brd

J10  SCONN288_ADR50017P087CC  SCONN288_ADR50017-P087CC IO  pkg DDR288S_1-1VXB  page 91
  VIN_BULK0  = P12V_S3_AUX_CPU0_NVDIMM
  RFU0  = TP_CHE_CPU0_DIMM2_FRU_0
  VIN_MGMT  = P3V3_AUX
  HSCL  = I3C_SPD_DDREFGH_CPU0_LVC1_SCL_1
  HSDA  = I3C_SPD_DDREFGH_CPU0_LVC1_SDA
  VSS0  = GND
  DQ0_A  = M_E_CPU0_SA_DQ<0>
  VSS1  = GND
  DQ1_A  = M_E_CPU0_SA_DQ<1>
  VSS2  = GND
  DQS0_A_T  = M_E_CPU0_SA_DQS_DP<0>
  DQS0_A_C  = M_E_CPU0_SA_DQS_DN<0>
  VSS3  = GND
  DQ4_A  = M_E_CPU0_SA_DQ<4>
  VSS4  = GND
  DQ5_A  = M_E_CPU0_SA_DQ<5>
  VSS5  = GND
  DQ8_A  = M_E_CPU0_SA_DQ<8>
  VSS6  = GND
  DQ9_A  = M_E_CPU0_SA_DQ<9>
  VSS7  = GND
  DQS1_A_T  = M_E_CPU0_SA_DQS_DP<1>
  DQS1_A_C  = M_E_CPU0_SA_DQS_DN<1>
  VSS8  = GND
  DQ12_A  = M_E_CPU0_SA_DQ<12>
  VSS9  = GND
  DQ13_A  = M_E_CPU0_SA_DQ<13>
  VSS10  = GND
  DQ16_A  = M_E_CPU0_SA_DQ<16>
  VSS11  = GND
  DQ17_A  = M_E_CPU0_SA_DQ<17>
  VSS12  = GND
  DQS2_A_T  = M_E_CPU0_SA_DQS_DP<2>
  DQS2_A_C  = M_E_CPU0_SA_DQS_DN<2>
  VSS13  = GND
  DQ20_A  = M_E_CPU0_SA_DQ<20>
  VSS14  = GND
  DQ21_A  = M_E_CPU0_SA_DQ<21>
  VSS15  = GND
  DQ24_A  = M_E_CPU0_SA_DQ<24>
  VSS16  = GND
  DQ25_A  = M_E_CPU0_SA_DQ<25>
  VSS17  = GND
  DQS3_A_T  = M_E_CPU0_SA_DQS_DP<3>
  DQS3_A_C  = M_E_CPU0_SA_DQS_DN<3>
  VSS18  = GND
  DQ28_A  = M_E_CPU0_SA_DQ<28>
  VSS19  = GND
  DQ29_A  = M_E_CPU0_SA_DQ<29>
  VSS20  = GND
  CB0_A  = M_E_CPU0_SA_CB<0>
  VSS21  = GND
  CB1_A  = M_E_CPU0_SA_CB<1>
  VSS22  = GND
  DQS4_A_T  = M_E_CPU0_SA_DQS_DP<4>
  DQS4_A_C  = M_E_CPU0_SA_DQS_DN<4>
  VSS23  = GND
  CB4_A  = M_E_CPU0_SA_CB<4>
  VSS24  = GND
  CB5_A  = M_E_CPU0_SA_CB<5>
  VSS25  = GND
  ALERT_N  = M_E_CPU0_ALERT_N
  VSS26  = GND
  CS0_A_N  = M_E_CPU0_SA_CS_N<2>
  VSS27  = GND
  CA0_A  = M_E_CPU0_SA_CA<0>
  VSS28  = GND
  CA2_A  = M_E_CPU0_SA_CA<2>
  VSS29  = GND
  CA4_A  = M_E_CPU0_SA_CA<4>
  VSS30  = GND
  CA6_A  = M_E_CPU0_SA_CA<6>
  VSS31  = GND
  PAR_A  = M_E_CPU0_SA_PAR
  VSS32  = GND
  CA0_B  = M_E_CPU0_SB_CA<0>
  VSS33  = GND
  CA2_B  = M_E_CPU0_SB_CA<2>
  VSS34  = GND
  CA4_B  = M_E_CPU0_SB_CA<4>
  VSS35  = GND
  CA6_B  = M_E_CPU0_SB_CA<6>
  VSS36  = GND
  CS0_B_N  = M_E_CPU0_SB_CS_N<2>
  VSS37  = GND
  \lbd||rsp_a_n\  = M_E_CPU0_SA_RSP<1>
  \lbs||rsp_b_n\  = M_E_CPU0_SB_RSP<1>
  VSS38  = GND
  CB4_B  = M_E_CPU0_SB_CB<4>
  VSS39  = GND
  CB5_B  = M_E_CPU0_SB_CB<5>
  VSS40  = GND
  \dqs9_b_t||tdqs9_b_t||dbi4_b_n\  = M_E_CPU0_SB_DQS_DP<9>
  \dqs9_b_c||tdqs9_b_c\  = M_E_CPU0_SB_DQS_DN<9>
  VSS41  = GND
  CB0_B  = M_E_CPU0_SB_CB<0>
  VSS42  = GND
  CB1_B  = M_E_CPU0_SB_CB<1>
  VSS43  = GND
  DQ0_B  = M_E_CPU0_SB_DQ<0>
  VSS44  = GND
  DQ1_B  = M_E_CPU0_SB_DQ<1>
  VSS45  = GND
  DQS0_B_T  = M_E_CPU0_SB_DQS_DP<0>
  DQS0_B_C  = M_E_CPU0_SB_DQS_DN<0>
  VSS46  = GND
  DQ4_B  = M_E_CPU0_SB_DQ<4>
  VSS47  = GND
  DQ5_B  = M_E_CPU0_SB_DQ<5>
  VSS48  = GND
  DQ8_B  = M_E_CPU0_SB_DQ<8>
  VSS49  = GND
  DQ9_B  = M_E_CPU0_SB_DQ<9>
  VSS50  = GND
  DQS1_B_T  = M_E_CPU0_SB_DQS_DP<1>
  DQS1_B_C  = M_E_CPU0_SB_DQS_DN<1>
  VSS51  = GND
  DQ12_B  = M_E_CPU0_SB_DQ<12>
  VSS52  = GND
  DQ13_B  = M_E_CPU0_SB_DQ<13>
  VSS53  = GND
  DQ16_B  = M_E_CPU0_SB_DQ<16>
  VSS54  = GND
  DQ17_B  = M_E_CPU0_SB_DQ<17>
  VSS55  = GND
  DQS2_B_T  = M_E_CPU0_SB_DQS_DP<2>
  DQS2_B_C  = M_E_CPU0_SB_DQS_DN<2>
  VSS56  = GND
  DQ20_B  = M_E_CPU0_SB_DQ<20>
  VSS57  = GND
  DQ21_B  = M_E_CPU0_SB_DQ<21>
  VSS58  = GND
  DQ24_B  = M_E_CPU0_SB_DQ<24>
  VSS59  = GND
  DQ25_B  = M_E_CPU0_SB_DQ<25>
  VSS60  = GND
  DQS3_B_T  = M_E_CPU0_SB_DQS_DP<3>
  DQS3_B_C  = M_E_CPU0_SB_DQS_DN<3>
  VSS61  = GND
  DQ28_B  = M_E_CPU0_SB_DQ<28>
  VSS62  = GND
  DQ29_B  = M_E_CPU0_SB_DQ<29>
  VSS63  = GND
  RFU1  = TP_CHE_CPU0_DIMM2_FRU_1
  VIN_BULK1  = P12V_S3_AUX_CPU0_NVDIMM
  VIN_BULK2  = P12V_S3_AUX_CPU0_NVDIMM
  \pwr_good||fail_n\  = PWRGD_CHE_CPU0_DIMM2
  HSA  = PD_CHE_CPU0_DIMM2_SAA
  RFU2  = TP_CHE_CPU0_DIMM2_FRU_2
  RFU3  = TP_CHE_CPU0_DIMM2_FRU_3
  VSS64  = GND
  DQ2_A  = M_E_CPU0_SA_DQ<2>
  VSS65  = GND
  DQ3_A  = M_E_CPU0_SA_DQ<3>
  VSS66  = GND
  \dqs5_a_c||tdqs5_a_c||dqs5_a_t||tdqs5_a_t\  = M_E_CPU0_SA_DQS_DN<5>
  \dqs5_a_t||tdqs5_a_t\  = M_E_CPU0_SA_DQS_DP<5>
  VSS67  = GND
  DQ6_A  = M_E_CPU0_SA_DQ<6>
  VSS68  = GND
  DQ7_A  = M_E_CPU0_SA_DQ<7>
  VSS69  = GND
  DQ10_A  = M_E_CPU0_SA_DQ<10>
  VSS70  = GND
  DQ11_A  = M_E_CPU0_SA_DQ<11>
  VSS71  = GND
  \dqs6_a_c||tdqs6_a_c||dqs6_a_t||tdqs6_a_t\  = M_E_CPU0_SA_DQS_DN<6>
  \dqs6_a_t||tdqs6_a_t\  = M_E_CPU0_SA_DQS_DP<6>
  VSS72  = GND
  DQ14_A  = M_E_CPU0_SA_DQ<14>
  VSS73  = GND
  DQ15_A  = M_E_CPU0_SA_DQ<15>
  VSS74  = GND
  DQ18_A  = M_E_CPU0_SA_DQ<18>
  VSS75  = GND
  DQ19_A  = M_E_CPU0_SA_DQ<19>
  VSS76  = GND
  \dqs7_a_c||tdqs7_a_c\  = M_E_CPU0_SA_DQS_DN<7>
  \dqs7_a_t||tdqs7_a_t\  = M_E_CPU0_SA_DQS_DP<7>
  VSS77  = GND
  DQ22_A  = M_E_CPU0_SA_DQ<22>
  VSS78  = GND
  DQ23_A  = M_E_CPU0_SA_DQ<23>
  VSS79  = GND
  DQ26_A  = M_E_CPU0_SA_DQ<26>
  VSS80  = GND
  DQ27_A  = M_E_CPU0_SA_DQ<27>
  VSS81  = GND
  \dqs8_a_c||tdqs8_a_c\  = M_E_CPU0_SA_DQS_DN<8>
  \dqs8_a_t||tdqs8_a_t\  = M_E_CPU0_SA_DQS_DP<8>
  VSS82  = GND
  DQ30_A  = M_E_CPU0_SA_DQ<30>
  VSS83  = GND
  DQ31_A  = M_E_CPU0_SA_DQ<31>
  VSS84  = GND
  CB2_A  = M_E_CPU0_SA_CB<2>
  VSS85  = GND
  CB3_A  = M_E_CPU0_SA_CB<3>
  VSS86  = GND
  \dqs9_a_c||tdqs9_a_c\  = M_E_CPU0_SA_DQS_DN<9>
  \dqs9_a_t||tdqs9_a_t\  = M_E_CPU0_SA_DQS_DP<9>
  VSS87  = GND
  CB6_A  = M_E_CPU0_SA_CB<6>
  VSS88  = GND
  CB7_A  = M_E_CPU0_SA_CB<7>
  VSS89  = GND
  RESET_N  = RST_M_EF_CPU0_FPGA_N
  VSS90  = GND
  CS1_A_N  = M_E_CPU0_SA_CS_N<3>
  VSS91  = GND
  CA1_A  = M_E_CPU0_SA_CA<1>
  VSS92  = GND
  CA3_A  = M_E_CPU0_SA_CA<3>
  VSS93  = GND
  CA5_A  = M_E_CPU0_SA_CA<5>
  VSS94  = GND
  CK_T  = M_E_CPU0_CLK_DP<1>
  CK_C  = M_E_CPU0_CLK_DN<1>
  VSS95  = GND
  RFU4  = TP_CHE_CPU0_DIMM2_FRU_4
  CA1_B  = M_E_CPU0_SB_CA<1>
  VSS96  = GND
  CA3_B  = M_E_CPU0_SB_CA<3>
  VSS97  = GND
  CA5_B  = M_E_CPU0_SB_CA<5>
  VSS98  = GND
  PAR_B  = M_E_CPU0_SB_PAR
  VSS99  = GND
  CS1_B_N  = M_E_CPU0_SB_CS_N<3>
  VSS100  = GND
  RFU5  = TP_CHE_CPU0_DIMM2_FRU_5
  RFU6  = TP_CHE_CPU0_DIMM2_FRU_6
  VSS101  = GND
  CB6_B  = M_E_CPU0_SB_CB<6>
  VSS102  = GND
  CB7_B  = M_E_CPU0_SB_CB<7>
  VSS103  = GND
  DQS4_B_C  = M_E_CPU0_SB_DQS_DN<4>
  DQS4_B_T  = M_E_CPU0_SB_DQS_DP<4>
  VSS104  = GND
  CB2_B  = M_E_CPU0_SB_CB<2>
  VSS105  = GND
  CB3_B  = M_E_CPU0_SB_CB<3>
  VSS106  = GND
  DQ2_B  = M_E_CPU0_SB_DQ<2>
  VSS107  = GND
  DQ3_B  = M_E_CPU0_SB_DQ<3>
  VSS108  = GND
  \dqs5_b_c||tdqs5_b_c\  = M_E_CPU0_SB_DQS_DN<5>
  \dqs5_b_t||tdqs5_b_t\  = M_E_CPU0_SB_DQS_DP<5>
  VSS109  = GND
  DQ6_B  = M_E_CPU0_SB_DQ<6>
  VSS110  = GND
  DQ7_B  = M_E_CPU0_SB_DQ<7>
  VSS111  = GND
  DQ10_B  = M_E_CPU0_SB_DQ<10>
  VSS112  = GND
  DQ11_B  = M_E_CPU0_SB_DQ<11>
  VSS113  = GND
  \dqs6_b_c||tdqs6_b_c\  = M_E_CPU0_SB_DQS_DN<6>
  \dqs6_b_t||tdqs6_b_t\  = M_E_CPU0_SB_DQS_DP<6>
  VSS114  = GND
  DQ14_B  = M_E_CPU0_SB_DQ<14>
  VSS115  = GND
  DQ15_B  = M_E_CPU0_SB_DQ<15>
  VSS116  = GND
  DQ18_B  = M_E_CPU0_SB_DQ<18>
  VSS117  = GND
  DQ19_B  = M_E_CPU0_SB_DQ<19>
  VSS118  = GND
  \dqs7_b_c||tdqs7_b_c\  = M_E_CPU0_SB_DQS_DN<7>
  \dqs7_b_t||tdqs7_b_t\  = M_E_CPU0_SB_DQS_DP<7>
  VSS119  = GND
  DQ22_B  = M_E_CPU0_SB_DQ<22>
  VSS120  = GND
  DQ23_B  = M_E_CPU0_SB_DQ<23>
  VSS121  = GND
  DQ26_B  = M_E_CPU0_SB_DQ<26>
  VSS122  = GND
  DQ27_B  = M_E_CPU0_SB_DQ<27>
  VSS123  = GND
  \dqs8_b_c||tdqs8_b_c\  = M_E_CPU0_SB_DQS_DN<8>
  \dqs8_b_t||tdqs8_b_t\  = M_E_CPU0_SB_DQS_DP<8>
  VSS124  = GND
  DQ30_B  = M_E_CPU0_SB_DQ<30>
  VSS125  = GND
  DQ31_B  = M_E_CPU0_SB_DQ<31>
  VSS126  = GND
  G1  = GND
  G2  = GND
  G3  = GND

(kicad_pcb
	(version 20260206)
	(generator "pcbnew")
	(generator_version "10.0")
	(general
		(thickness 1.6)
		(legacy_teardrops no)
	)
	(paper "A4")
	(title_block
		(title "03242023_DA0F0TMBIJ0_F0T_Motherboard_J_brd_V01_OCP.brd")
		(comment 1 "Grand Teton / footprint 1607 of 6105 (J10), pads 183-228 of 291")
	)
	(layers
		(0 "F.Cu" signal "TOP")
		(4 "In1.Cu" signal "GND")
		(6 "In2.Cu" signal "IN1")
		(8 "In3.Cu" signal "GND1")
		(10 "In4.Cu" signal "IN2")
		(12 "In5.Cu" signal "GND2")
		(14 "In6.Cu" signal "IN3")
		(16 "In7.Cu" signal "GND3")
		(18 "In8.Cu" signal "VCC")
		(20 "In9.Cu" signal "VCC1")
		(22 "In10.Cu" signal "GND4")
		(24 "In11.Cu" signal "IN4")
		(26 "In12.Cu" signal "GND5")
		(28 "In13.Cu" signal "IN5")
		(30 "In14.Cu" signal "GND6")
		(32 "In15.Cu" signal "IN6")
		(34 "In16.Cu" signal "GND7")
		(2 "B.Cu" signal "BOTTOM")
		(9 "F.Adhes" user "F.Adhesive")
		(11 "B.Adhes" user "B.Adhesive")
		(13 "F.Paste" user "Package Geometry/Pastemask Top")
		(15 "B.Paste" user "Package Geometry/Pastemask Bottom")
		(5 "F.SilkS" user "Ref Des/Silkscreen Top")
		(7 "B.SilkS" user "Ref Des/Silkscreen Bottom")
		(1 "F.Mask" user "Board Geometry/Soldermask Top")
		(3 "B.Mask" user "Board Geometry/Soldermask Bottom")
		(17 "Dwgs.User" user "User.Drawings")
		(19 "Cmts.User" user "User.Comments")
		(21 "Eco1.User" user "User.Eco1")
		(23 "Eco2.User" user "User.Eco2")
		(25 "Edge.Cuts" user "Board Geometry/Outline")
		(27 "Margin" user)
		(31 "F.CrtYd" user "Package Geometry/Place Bound Top")
		(29 "B.CrtYd" user "Package Geometry/Place Bound Bottom")
		(35 "F.Fab" user "Ref Des/Assembly Top")
		(33 "B.Fab" user "Ref Des/Assembly Bottom")
	)
	(footprint ""
		(layer "F.Cu")
		(at 408.803348 -258.091686)
		(property "Reference" "J10"
			(at -3.683 -81.702148 0)
			(unlocked yes)
			(layer "F.SilkS")
			(effects
				(font
					(size 0.7874 0.5842)
					(thickness 0.1524)
				)
				(justify left)
			)
		)
		(property "Value" ""
			(at 0 0 0)
			(layer "F.Fab")
			(effects
				(font
					(size 1.27 1.27)
				)
			)
		)
		(duplicate_pad_numbers_are_jumpers no)
		(pad "183" smd rect
			(at 2.050034 -31.025084 270)
			(size 0.519938 1.4986)
			(layers "F.Cu" "F.Mask" "F.Paste")
			(net "M_E_CPU0_SA_DQ<23>")
		)
		(pad "184" smd rect
			(at 2.050034 -30.174946 270)
			(size 0.519938 1.4986)
			(layers "F.Cu" "F.Mask" "F.Paste")
			(net "GND")
		)
		(pad "185" smd rect
			(at 2.050034 -29.325062 270)
			(size 0.519938 1.4986)
			(layers "F.Cu" "F.Mask" "F.Paste")
			(net "M_E_CPU0_SA_DQ<26>")
		)
		(pad "186" smd rect
			(at 2.050034 -28.474924 270)
			(size 0.519938 1.4986)
			(layers "F.Cu" "F.Mask" "F.Paste")
			(net "GND")
		)
		(pad "187" smd rect
			(at 2.050034 -27.62504 270)
			(size 0.519938 1.4986)
			(layers "F.Cu" "F.Mask" "F.Paste")
			(net "M_E_CPU0_SA_DQ<27>")
		)
		(pad "188" smd rect
			(at 2.050034 -26.774902 270)
			(size 0.519938 1.4986)
			(layers "F.Cu" "F.Mask" "F.Paste")
			(net "GND")
		)
		(pad "189" smd rect
			(at 2.050034 -25.925018 270)
			(size 0.519938 1.4986)
			(layers "F.Cu" "F.Mask" "F.Paste")
			(net "M_E_CPU0_SA_DQS_DN<8>")
		)
		(pad "190" smd rect
			(at 2.050034 -25.07488 270)
			(size 0.519938 1.4986)
			(layers "F.Cu" "F.Mask" "F.Paste")
			(net "M_E_CPU0_SA_DQS_DP<8>")
		)
		(pad "191" smd rect
			(at 2.050034 -24.224996 270)
			(size 0.519938 1.4986)
			(layers "F.Cu" "F.Mask" "F.Paste")
			(net "GND")
		)
		(pad "192" smd rect
			(at 2.050034 -23.375112 270)
			(size 0.519938 1.4986)
			(layers "F.Cu" "F.Mask" "F.Paste")
			(net "M_E_CPU0_SA_DQ<30>")
		)
		(pad "193" smd rect
			(at 2.050034 -22.524974 270)
			(size 0.519938 1.4986)
			(layers "F.Cu" "F.Mask" "F.Paste")
			(net "GND")
		)
		(pad "194" smd rect
			(at 2.050034 -21.67509 270)
			(size 0.519938 1.4986)
			(layers "F.Cu" "F.Mask" "F.Paste")
			(net "M_E_CPU0_SA_DQ<31>")
		)
		(pad "195" smd rect
			(at 2.050034 -20.824952 270)
			(size 0.519938 1.4986)
			(layers "F.Cu" "F.Mask" "F.Paste")
			(net "GND")
		)
		(pad "196" smd rect
			(at 2.050034 -19.975068 270)
			(size 0.519938 1.4986)
			(layers "F.Cu" "F.Mask" "F.Paste")
			(net "M_E_CPU0_SA_CB<2>")
		)
		(pad "197" smd rect
			(at 2.050034 -19.12493 270)
			(size 0.519938 1.4986)
			(layers "F.Cu" "F.Mask" "F.Paste")
			(net "GND")
		)
		(pad "198" smd rect
			(at 2.050034 -18.275046 270)
			(size 0.519938 1.4986)
			(layers "F.Cu" "F.Mask" "F.Paste")
			(net "M_E_CPU0_SA_CB<3>")
		)
		(pad "199" smd rect
			(at 2.050034 -17.424908 270)
			(size 0.519938 1.4986)
			(layers "F.Cu" "F.Mask" "F.Paste")
			(net "GND")
		)
		(pad "200" smd rect
			(at 2.050034 -16.575024 270)
			(size 0.519938 1.4986)
			(layers "F.Cu" "F.Mask" "F.Paste")
			(net "M_E_CPU0_SA_DQS_DN<9>")
		)
		(pad "201" smd rect
			(at 2.050034 -15.724886 270)
			(size 0.519938 1.4986)
			(layers "F.Cu" "F.Mask" "F.Paste")
			(net "M_E_CPU0_SA_DQS_DP<9>")
		)
		(pad "202" smd rect
			(at 2.050034 -14.875002 270)
			(size 0.519938 1.4986)
			(layers "F.Cu" "F.Mask" "F.Paste")
			(net "GND")
		)
		(pad "203" smd rect
			(at 2.050034 -14.025118 270)
			(size 0.519938 1.4986)
			(layers "F.Cu" "F.Mask" "F.Paste")
			(net "M_E_CPU0_SA_CB<6>")
		)
		(pad "204" smd rect
			(at 2.050034 -13.17498 270)
			(size 0.519938 1.4986)
			(layers "F.Cu" "F.Mask" "F.Paste")
			(net "GND")
		)
		(pad "205" smd rect
			(at 2.050034 -12.325096 270)
			(size 0.519938 1.4986)
			(layers "F.Cu" "F.Mask" "F.Paste")
			(net "M_E_CPU0_SA_CB<7>")
		)
		(pad "206" smd rect
			(at 2.050034 -11.474958 270)
			(size 0.519938 1.4986)
			(layers "F.Cu" "F.Mask" "F.Paste")
			(net "GND")
		)
		(pad "207" smd rect
			(at 2.050034 -10.625074 270)
			(size 0.519938 1.4986)
			(layers "F.Cu" "F.Mask" "F.Paste")
			(net "RST_M_EF_CPU0_FPGA_N")
		)
		(pad "208" smd rect
			(at 2.050034 -9.774936 270)
			(size 0.519938 1.4986)
			(layers "F.Cu" "F.Mask" "F.Paste")
			(net "GND")
		)
		(pad "209" smd rect
			(at 2.050034 -8.925052 270)
			(size 0.519938 1.4986)
			(layers "F.Cu" "F.Mask" "F.Paste")
			(net "M_E_CPU0_SA_CS_N<3>")
		)
		(pad "210" smd rect
			(at 2.050034 -8.074914 270)
			(size 0.519938 1.4986)
			(layers "F.Cu" "F.Mask" "F.Paste")
			(net "GND")
		)
		(pad "211" smd rect
			(at 2.050034 -7.22503 270)
			(size 0.519938 1.4986)
			(layers "F.Cu" "F.Mask" "F.Paste")
			(net "M_E_CPU0_SA_CA<1>")
		)
		(pad "212" smd rect
			(at 2.050034 -6.374892 270)
			(size 0.519938 1.4986)
			(layers "F.Cu" "F.Mask" "F.Paste")
			(net "GND")
		)
		(pad "213" smd rect
			(at 2.050034 -5.525008 270)
			(size 0.519938 1.4986)
			(layers "F.Cu" "F.Mask" "F.Paste")
			(net "M_E_CPU0_SA_CA<3>")
		)
		(pad "214" smd rect
			(at 2.050034 -4.675124 270)
			(size 0.519938 1.4986)
			(layers "F.Cu" "F.Mask" "F.Paste")
			(net "GND")
		)
		(pad "215" smd rect
			(at 2.050034 -3.824986 270)
			(size 0.519938 1.4986)
			(layers "F.Cu" "F.Mask" "F.Paste")
			(net "M_E_CPU0_SA_CA<5>")
		)
		(pad "216" smd rect
			(at 2.050034 -2.975102 270)
			(size 0.519938 1.4986)
			(layers "F.Cu" "F.Mask" "F.Paste")
			(net "GND")
		)
		(pad "217" smd rect
			(at 2.050034 -2.124964 270)
			(size 0.519938 1.4986)
			(layers "F.Cu" "F.Mask" "F.Paste")
			(net "M_E_CPU0_CLK_DP<1>")
		)
		(pad "218" smd rect
			(at 2.050034 -1.27508 270)
			(size 0.519938 1.4986)
			(layers "F.Cu" "F.Mask" "F.Paste")
			(net "M_E_CPU0_CLK_DN<1>")
		)
		(pad "219" smd rect
			(at 2.050034 -0.424942 270)
			(size 0.519938 1.4986)
			(layers "F.Cu" "F.Mask" "F.Paste")
			(net "GND")
		)
		(pad "220" smd rect
			(at 2.050034 5.525008 270)
			(size 0.519938 1.4986)
			(layers "F.Cu" "F.Mask" "F.Paste")
			(net "TP_CHE_CPU0_DIMM2_FRU_4")
		)
		(pad "221" smd rect
			(at 2.050034 6.374892 270)
			(size 0.519938 1.4986)
			(layers "F.Cu" "F.Mask" "F.Paste")
			(net "M_E_CPU0_SB_CA<1>")
		)
		(pad "222" smd rect
			(at 2.050034 7.22503 270)
			(size 0.519938 1.4986)
			(layers "F.Cu" "F.Mask" "F.Paste")
			(net "GND")
		)
		(pad "223" smd rect
			(at 2.050034 8.074914 270)
			(size 0.519938 1.4986)
			(layers "F.Cu" "F.Mask" "F.Paste")
			(net "M_E_CPU0_SB_CA<3>")
		)
		(pad "224" smd rect
			(at 2.050034 8.925052 270)
			(size 0.519938 1.4986)
			(layers "F.Cu" "F.Mask" "F.Paste")
			(net "GND")
		)
		(pad "225" smd rect
			(at 2.050034 9.774936 270)
			(size 0.519938 1.4986)
			(layers "F.Cu" "F.Mask" "F.Paste")
			(net "M_E_CPU0_SB_CA<5>")
		)
		(pad "226" smd rect
			(at 2.050034 10.625074 270)
			(size 0.519938 1.4986)
			(layers "F.Cu" "F.Mask" "F.Paste")
			(net "GND")
		)
		(pad "227" smd rect
			(at 2.050034 11.474958 270)
			(size 0.519938 1.4986)
			(layers "F.Cu" "F.Mask" "F.Paste")
			(net "M_E_CPU0_SB_PAR")
		)
		(pad "228" smd rect
			(at 2.050034 12.325096 270)
			(size 0.519938 1.4986)
			(layers "F.Cu" "F.Mask" "F.Paste")
			(net "GND")
		)
	)
)
